# T6G (Grand Teton) — schematic netlist excerpt (pin names and nets, part order shuffled) for the footprints in the layout excerpt that follows; sources: Cadence DE-HDL packaged netlist, KiCad conversion of 04192023_DAF0TMB3IC0_F0TG_MB_C_brd_V02_OCP.brd

J63  PICOPROBE_BXA  DELTA-L 4.0 EMPTY  pkg TRIANG_LAUNCH_3PXB  page 229
  \1_p\  = DELTA_L_85_5INCH_TOP_DP
  \2_n\  = DELTA_L_85_5INCH_TOP_DN
  \3_g\  = DELTA_L_GND_1

R731  Q_RES  0 5% CHIP  pkg 0201LF  page 331 : A = RST_RT_CPU1_P1_PERST_N ; B = RST_RT_CPU1_P1_PERST_R_N

(kicad_pcb
	(version 20260206)
	(generator "pcbnew")
	(generator_version "10.0")
	(general
		(thickness 1.6)
		(legacy_teardrops no)
	)
	(paper "A4")
	(title_block
		(title "04192023_DAF0TMB3IC0_F0TG_MB_C_brd_V02_OCP.brd")
		(comment 1 "Grand Teton / footprints 546-547 of 8354")
	)
	(layers
		(0 "F.Cu" signal "TOP")
		(4 "In1.Cu" signal "GND")
		(6 "In2.Cu" signal "IN1")
		(8 "In3.Cu" signal "GND1")
		(10 "In4.Cu" signal "IN2")
		(12 "In5.Cu" signal "GND2")
		(14 "In6.Cu" signal "IN3")
		(16 "In7.Cu" signal "GND3")
		(18 "In8.Cu" signal "VCC")
		(20 "In9.Cu" signal "VCC1")
		(22 "In10.Cu" signal "GND4")
		(24 "In11.Cu" signal "IN4")
		(26 "In12.Cu" signal "GND5")
		(28 "In13.Cu" signal "IN5")
		(30 "In14.Cu" signal "GND6")
		(32 "In15.Cu" signal "IN6")
		(34 "In16.Cu" signal "GND7")
		(2 "B.Cu" signal "BOTTOM")
		(9 "F.Adhes" user "F.Adhesive")
		(11 "B.Adhes" user "B.Adhesive")
		(13 "F.Paste" user "Package Geometry/Pastemask Top")
		(15 "B.Paste" user "Package Geometry/Pastemask Bottom")
		(5 "F.SilkS" user "Ref Des/Silkscreen Top")
		(7 "B.SilkS" user "Ref Des/Silkscreen Bottom")
		(1 "F.Mask" user "Board Geometry/Soldermask Top")
		(3 "B.Mask" user "Board Geometry/Soldermask Bottom")
		(17 "Dwgs.User" user "User.Drawings")
		(19 "Cmts.User" user "User.Comments")
		(21 "Eco1.User" user "User.Eco1")
		(23 "Eco2.User" user "User.Eco2")
		(25 "Edge.Cuts" user "Board Geometry/Outline")
		(27 "Margin" user)
		(31 "F.CrtYd" user "Package Geometry/Place Bound Top")
		(29 "B.CrtYd" user "Package Geometry/Place Bound Bottom")
		(35 "F.Fab" user "Ref Des/Assembly Top")
		(33 "B.Fab" user "Ref Des/Assembly Bottom")
	)
	(footprint ""
		(layer "F.Cu")
		(at 366.288574 -5.077206 180)
		(property "Reference" "J63"
			(at -4.50723 -1.072642 90)
			(unlocked yes)
			(layer "F.SilkS")
			(effects
				(font
					(size 0.7874 0.5842)
					(thickness 0.1524)
				)
				(justify left)
			)
		)
		(property "Value" ""
			(at 0 0 180)
			(layer "F.Fab")
			(effects
				(font
					(size 1.27 1.27)
				)
			)
		)
		(duplicate_pad_numbers_are_jumpers no)
		(fp_line
			(start 1.2192 2.06756)
			(end -1.2192 2.06756)
			(stroke
				(width 0.1524)
				(type default)
			)
			(layer "F.SilkS")
		)
		(fp_line
			(start 1.2192 -2.06756)
			(end 1.2192 2.06756)
			(stroke
				(width 0.1524)
				(type default)
			)
			(layer "F.SilkS")
		)
		(fp_line
			(start -1.2192 2.06756)
			(end -1.2192 -2.06756)
			(stroke
				(width 0.1524)
				(type default)
			)
			(layer "F.SilkS")
		)
		(fp_line
			(start -1.2192 -2.06756)
			(end 1.2192 -2.06756)
			(stroke
				(width 0.1524)
				(type default)
			)
			(layer "F.SilkS")
		)
		(pad "" np_thru_hole circle
			(at -2.8829 -1.27 90)
			(size 1.0414 1.0414)
			(drill 1.0414)
			(layers "*.Cu" "*.Mask")
			(clearance 0.381)
			(thermal_gap 0.381)
		)
		(pad "" np_thru_hole circle
			(at -2.8829 1.27 90)
			(size 1.0414 1.0414)
			(drill 1.0414)
			(layers "*.Cu" "*.Mask")
			(clearance 0.381)
			(thermal_gap 0.381)
		)
		(pad "" np_thru_hole circle
			(at 3.4671 -1.27 90)
			(size 1.0414 1.0414)
			(drill 1.0414)
			(layers "*.Cu" "*.Mask")
			(clearance 0.381)
			(thermal_gap 0.381)
		)
		(pad "" np_thru_hole circle
			(at 3.4671 1.27 90)
			(size 1.0414 1.0414)
			(drill 1.0414)
			(layers "*.Cu" "*.Mask")
			(clearance 0.381)
			(thermal_gap 0.381)
		)
		(pad "1" smd rect
			(at 0.8255 -0.249936 90)
			(size 0.3048 0.508)
			(layers "F.Cu" "F.Mask" "F.Paste")
			(net "DELTA_L_85_5INCH_TOP_DP")
		)
		(pad "2" smd rect
			(at 0.8255 0.249936 90)
			(size 0.3048 0.508)
			(layers "F.Cu" "F.Mask" "F.Paste")
			(net "DELTA_L_85_5INCH_TOP_DN")
		)
		(pad "3" smd circle
			(at 0 0 180)
			(size 0 0)
			(layers "F.Cu" "F.Mask" "F.Paste")
			(net "DELTA_L_GND_1")
		)
		(zone
			(layer "F.Cu")
			(hatch none 0.5)
			(connect_pads
				(clearance 0)
			)
			(min_thickness 0.25)
			(keepout
				(tracks not_allowed)
				(vias allowed)
				(pads allowed)
				(copperpour not_allowed)
				(footprints allowed)
			)
			(placement
				(enabled no)
				(sheetname "")
			)
			(fill
				(thermal_gap 0.5)
				(thermal_bridge_width 0.5)
				(island_removal_mode 0)
			)
			(polygon
				(pts
					(xy 365.170974 -4.528566) (xy 365.170974 -4.62407) (xy 365.767874 -4.62407) (xy 365.767874 -5.03047)
					(xy 365.170974 -5.03047) (xy 365.170974 -5.123942) (xy 365.767874 -5.123942) (xy 365.767874 -5.530342)
					(xy 365.170974 -5.530342) (xy 365.170974 -5.625846) (xy 365.869474 -5.625846) (xy 365.869474 -4.528566)
				)
			)
		)
		(zone
			(layers "F.Cu" "B.Cu" "In1.Cu" "In2.Cu" "In3.Cu" "In4.Cu" "In5.Cu" "In6.Cu"
				"In7.Cu" "In8.Cu" "In9.Cu" "In10.Cu" "In11.Cu" "In12.Cu" "In13.Cu" "In14.Cu"
				"In15.Cu" "In16.Cu"
			)
			(hatch none 0.5)
			(connect_pads
				(clearance 0)
			)
			(min_thickness 0.25)
			(keepout
				(tracks not_allowed)
				(vias allowed)
				(pads allowed)
				(copperpour not_allowed)
				(footprints allowed)
			)
			(placement
				(enabled no)
				(sheetname "")
			)
			(fill
				(thermal_gap 0.5)
				(thermal_bridge_width 0.5)
				(island_removal_mode 0)
			)
			(polygon
				(pts
					(arc
						(start 363.748574 -6.347206)
						(mid 361.894374 -6.347206)
						(end 363.748574 -6.347206)
					)
				)
			)
		)
		(zone
			(layers "F.Cu" "B.Cu" "In1.Cu" "In2.Cu" "In3.Cu" "In4.Cu" "In5.Cu" "In6.Cu"
				"In7.Cu" "In8.Cu" "In9.Cu" "In10.Cu" "In11.Cu" "In12.Cu" "In13.Cu" "In14.Cu"
				"In15.Cu" "In16.Cu"
			)
			(hatch none 0.5)
			(connect_pads
				(clearance 0)
			)
			(min_thickness 0.25)
			(keepout
				(tracks not_allowed)
				(vias allowed)
				(pads allowed)
				(copperpour not_allowed)
				(footprints allowed)
			)
			(placement
				(enabled no)
				(sheetname "")
			)
			(fill
				(thermal_gap 0.5)
				(thermal_bridge_width 0.5)
				(island_removal_mode 0)
			)
			(polygon
				(pts
					(arc
						(start 363.748574 -3.807206)
						(mid 361.894374 -3.807206)
						(end 363.748574 -3.807206)
					)
				)
			)
		)
		(zone
			(layers "F.Cu" "B.Cu" "In1.Cu" "In2.Cu" "In3.Cu" "In4.Cu" "In5.Cu" "In6.Cu"
				"In7.Cu" "In8.Cu" "In9.Cu" "In10.Cu" "In11.Cu" "In12.Cu" "In13.Cu" "In14.Cu"
				"In15.Cu" "In16.Cu"
			)
			(hatch none 0.5)
			(connect_pads
				(clearance 0)
			)
			(min_thickness 0.25)
			(keepout
				(tracks not_allowed)
				(vias allowed)
				(pads allowed)
				(copperpour not_allowed)
				(footprints allowed)
			)
			(placement
				(enabled no)
				(sheetname "")
			)
			(fill
				(thermal_gap 0.5)
				(thermal_bridge_width 0.5)
				(island_removal_mode 0)
			)
			(polygon
				(pts
					(arc
						(start 370.098574 -6.347206)
						(mid 368.244374 -6.347206)
						(end 370.098574 -6.347206)
					)
				)
			)
		)
		(zone
			(layers "F.Cu" "B.Cu" "In1.Cu" "In2.Cu" "In3.Cu" "In4.Cu" "In5.Cu" "In6.Cu"
				"In7.Cu" "In8.Cu" "In9.Cu" "In10.Cu" "In11.Cu" "In12.Cu" "In13.Cu" "In14.Cu"
				"In15.Cu" "In16.Cu"
			)
			(hatch none 0.5)
			(connect_pads
				(clearance 0)
			)
			(min_thickness 0.25)
			(keepout
				(tracks not_allowed)
				(vias allowed)
				(pads allowed)
				(copperpour not_allowed)
				(footprints allowed)
			)
			(placement
				(enabled no)
				(sheetname "")
			)
			(fill
				(thermal_gap 0.5)
				(thermal_bridge_width 0.5)
				(island_removal_mode 0)
			)
			(polygon
				(pts
					(arc
						(start 370.098574 -3.807206)
						(mid 368.244374 -3.807206)
						(end 370.098574 -3.807206)
					)
				)
			)
		)
	)
	(footprint ""
		(layer "F.Cu")
		(at 100.696268 -395.6304 -90)
		(property "Reference" "R731"
			(at 0 0 270)
			(layer "F.SilkS")
			(hide yes)
			(effects
				(font
					(size 1.27 1.27)
				)
			)
		)
		(property "Value" ""
			(at 0 0 270)
			(layer "F.Fab")
			(effects
				(font
					(size 1.27 1.27)
				)
			)
		)
		(duplicate_pad_numbers_are_jumpers no)
		(fp_line
			(start -0.32512 0.175006)
			(end -0.32512 -0.175006)
			(stroke
				(width 0.1)
				(type default)
			)
			(layer "F.Fab")
		)
		(fp_line
			(start 0.32512 0.175006)
			(end -0.32512 0.175006)
			(stroke
				(width 0.1)
				(type default)
			)
			(layer "F.Fab")
		)
		(fp_line
			(start -0.32512 -0.175006)
			(end 0.32512 -0.175006)
			(stroke
				(width 0.1)
				(type default)
			)
			(layer "F.Fab")
		)
		(fp_line
			(start 0.32512 -0.175006)
			(end 0.32512 0.175006)
			(stroke
				(width 0.1)
				(type default)
			)
			(layer "F.Fab")
		)
		(pad "1" smd rect
			(at -0.2667 0 270)
			(size 0.3048 0.381)
			(layers "F.Cu" "F.Mask" "F.Paste")
			(net "RST_RT_CPU1_P1_PERST_N")
		)
		(pad "2" smd rect
			(at 0.2667 0 90)
			(size 0.3048 0.381)
			(layers "F.Cu" "F.Mask" "F.Paste")
			(net "RST_RT_CPU1_P1_PERST_R_N")
		)
	)
)
